(kicad_pcb
	(version 20260206)
	(generator "pcbnew")
	(generator_version "10.0")
	(general
		(thickness 1.6)
		(legacy_teardrops no)
	)
	(paper "A4")
	(title_block
		(title "peb — Lightning_PEB_BRD.brd")
		(comment 1 "Lightning (Wiwynn / Facebook NVMe JBOF) / footprints 1950-1956 of 2563")
	)
	(layers
		(0 "F.Cu" signal "TOP")
		(4 "In1.Cu" signal "L2GND")
		(6 "In2.Cu" signal "L3")
		(8 "In3.Cu" signal "L4VCC")
		(10 "In4.Cu" signal "L5VCC")
		(12 "In5.Cu" signal "L6")
		(14 "In6.Cu" signal "L7GND")
		(2 "B.Cu" signal "BOTTOM")
		(9 "F.Adhes" user "F.Adhesive")
		(11 "B.Adhes" user "B.Adhesive")
		(13 "F.Paste" user "Package Geometry/Pastemask Top")
		(15 "B.Paste" user "Package Geometry/Pastemask Bottom")
		(5 "F.SilkS" user "Ref Des/Silkscreen Top")
		(7 "B.SilkS" user "Ref Des/Silkscreen Bottom")
		(1 "F.Mask" user "Board Geometry/Soldermask Top")
		(3 "B.Mask" user "Board Geometry/Soldermask Bottom")
		(17 "Dwgs.User" user "User.Drawings")
		(19 "Cmts.User" user "User.Comments")
		(21 "Eco1.User" user "User.Eco1")
		(23 "Eco2.User" user "User.Eco2")
		(25 "Edge.Cuts" user "Board Geometry/Outline")
		(27 "Margin" user)
		(31 "F.CrtYd" user "Package Geometry/Place Bound Top")
		(29 "B.CrtYd" user "Package Geometry/Place Bound Bottom")
		(35 "F.Fab" user "Ref Des/Assembly Top")
		(33 "B.Fab" user "Ref Des/Assembly Bottom")
	)
	(footprint ""
		(layer "B.Cu")
		(at 241.681 -23.241)
		(property "Reference" "R810"
			(at 0 0 0)
			(layer "B.SilkS")
			(hide yes)
			(effects
				(font
					(size 1.27 1.27)
				)
				(justify mirror)
			)
		)
		(property "Value" "4K7R2F-GP"
			(at -0.064008 -3.993896 0)
			(unlocked yes)
			(layer "B.Fab")
			(hide yes)
			(effects
				(font
					(size 1.016 1.016)
					(thickness 0.1524)
				)
				(justify mirror)
			)
		)
		(property "Device Type" "R402H16"
			(at -0.064008 -5.517896 0)
			(unlocked yes)
			(layer "B.Fab")
			(hide yes)
			(effects
				(font
					(size 1.016 1.016)
					(thickness 0.1524)
				)
				(justify mirror)
			)
		)
		(duplicate_pad_numbers_are_jumpers no)
		(fp_line
			(start -0.508 -0.9398)
			(end 0.508 -0.9398)
			(stroke
				(width 0.1524)
				(type default)
			)
			(layer "B.SilkS")
		)
		(fp_line
			(start 0.508 -0.9398)
			(end 0.508 0.9398)
			(stroke
				(width 0.1524)
				(type default)
			)
			(layer "B.SilkS")
		)
		(fp_rect
			(start 0.508 0.9398)
			(end -0.508 -0.9398)
			(stroke
				(width 0)
				(type default)
			)
			(fill no)
			(layer "B.CrtYd")
		)
		(fp_rect
			(start 0.508 0.9398)
			(end -0.508 -0.9398)
			(stroke
				(width 0)
				(type default)
			)
			(fill no)
			(layer "B.Fab")
		)
		(pad "1" smd custom
			(at 0 -0.4445 180)
			(size 0.1397 0.1397)
			(layers "B.Cu" "B.Mask" "B.Paste")
			(net "GND")
			(options
				(clearance outline)
				(anchor circle)
			)
			(primitives
				(gr_poly
					(pts
						(arc
							(start -0.1778 0.2794)
							(mid -0.249642 0.249642)
							(end -0.2794 0.1778)
						)
						(arc
							(start -0.2794 -0.1778)
							(mid -0.249642 -0.249642)
							(end -0.1778 -0.2794)
						)
						(arc
							(start 0.1778 -0.2794)
							(mid 0.249642 -0.249642)
							(end 0.2794 -0.1778)
						)
						(arc
							(start 0.2794 0.1778)
							(mid 0.249642 0.249642)
							(end 0.1778 0.2794)
						)
					)
					(width 0)
					(fill yes)
				)
			)
		)
		(pad "2" smd custom
			(at 0 0.4445 180)
			(size 0.1397 0.1397)
			(layers "B.Cu" "B.Mask" "B.Paste")
			(net "BOOTSTRAP5")
			(options
				(clearance outline)
				(anchor circle)
			)
			(primitives
				(gr_poly
					(pts
						(arc
							(start -0.1778 0.2794)
							(mid -0.249642 0.249642)
							(end -0.2794 0.1778)
						)
						(arc
							(start -0.2794 -0.1778)
							(mid -0.249642 -0.249642)
							(end -0.1778 -0.2794)
						)
						(arc
							(start 0.1778 -0.2794)
							(mid 0.249642 -0.249642)
							(end 0.2794 -0.1778)
						)
						(arc
							(start 0.2794 0.1778)
							(mid 0.249642 0.249642)
							(end 0.1778 0.2794)
						)
					)
					(width 0)
					(fill yes)
				)
			)
		)
	)
	(footprint ""
		(layer "B.Cu")
		(at 77.769212 -186.545474)
		(property "Reference" "C415"
			(at 0 0 0)
			(layer "B.SilkS")
			(hide yes)
			(effects
				(font
					(size 1.27 1.27)
				)
				(justify mirror)
			)
		)
		(property "Value" "SCD1U25V2KX-2-GP"
			(at -1.1811 -2.7051 0)
			(unlocked yes)
			(layer "B.Fab")
			(hide yes)
			(effects
				(font
					(size 1.016 1.016)
					(thickness 0.1524)
				)
				(justify mirror)
			)
		)
		(property "Device Type" "C402H22"
			(at -1.1811 -4.2291 0)
			(unlocked yes)
			(layer "B.Fab")
			(hide yes)
			(effects
				(font
					(size 1.016 1.016)
					(thickness 0.1524)
				)
				(justify mirror)
			)
		)
		(duplicate_pad_numbers_are_jumpers no)
		(fp_rect
			(start 0.4318 0.9525)
			(end -0.4318 -0.9525)
			(stroke
				(width 0)
				(type default)
			)
			(fill no)
			(layer "B.CrtYd")
		)
		(fp_rect
			(start 0.4318 0.9525)
			(end -0.4318 -0.9525)
			(stroke
				(width 0)
				(type default)
			)
			(fill no)
			(layer "B.Fab")
		)
		(pad "1" smd custom
			(at 0 -0.4445 180)
			(size 0.1524 0.1524)
			(layers "B.Cu" "B.Mask" "B.Paste")
			(net "P3V3_STBY")
			(options
				(clearance outline)
				(anchor circle)
			)
			(primitives
				(gr_poly
					(pts
						(arc
							(start 0.3048 0.2032)
							(mid 0.275042 0.275042)
							(end 0.2032 0.3048)
						)
						(arc
							(start -0.2032 0.3048)
							(mid -0.275042 0.275042)
							(end -0.3048 0.2032)
						)
						(arc
							(start -0.3048 -0.2032)
							(mid -0.275042 -0.275042)
							(end -0.2032 -0.3048)
						)
						(arc
							(start 0.2032 -0.3048)
							(mid 0.275042 -0.275042)
							(end 0.3048 -0.2032)
						)
					)
					(width 0)
					(fill yes)
				)
			)
		)
		(pad "2" smd custom
			(at 0 0.4445 180)
			(size 0.1524 0.1524)
			(layers "B.Cu" "B.Mask" "B.Paste")
			(net "GND")
			(options
				(clearance outline)
				(anchor circle)
			)
			(primitives
				(gr_poly
					(pts
						(arc
							(start 0.3048 0.2032)
							(mid 0.275042 0.275042)
							(end 0.2032 0.3048)
						)
						(arc
							(start -0.2032 0.3048)
							(mid -0.275042 0.275042)
							(end -0.3048 0.2032)
						)
						(arc
							(start -0.3048 -0.2032)
							(mid -0.275042 -0.275042)
							(end -0.2032 -0.3048)
						)
						(arc
							(start 0.2032 -0.3048)
							(mid 0.275042 -0.275042)
							(end 0.3048 -0.2032)
						)
					)
					(width 0)
					(fill yes)
				)
			)
		)
	)
	(footprint ""
		(layer "B.Cu")
		(at 54.031642 -123.876816 -90)
		(property "Reference" "R466"
			(at 0 0 90)
			(layer "B.SilkS")
			(hide yes)
			(effects
				(font
					(size 1.27 1.27)
				)
				(justify mirror)
			)
		)
		(property "Value" "0R2J-2-GP"
			(at -0.064008 -3.993896 270)
			(unlocked yes)
			(layer "B.Fab")
			(hide yes)
			(effects
				(font
					(size 1.016 1.016)
					(thickness 0.1524)
				)
				(justify mirror)
			)
		)
		(property "Device Type" "R402H16"
			(at -0.064008 -5.517896 270)
			(unlocked yes)
			(layer "B.Fab")
			(hide yes)
			(effects
				(font
					(size 1.016 1.016)
					(thickness 0.1524)
				)
				(justify mirror)
			)
		)
		(duplicate_pad_numbers_are_jumpers no)
		(fp_line
			(start -0.508 -0.9398)
			(end 0.508 -0.9398)
			(stroke
				(width 0.1524)
				(type default)
			)
			(layer "B.SilkS")
		)
		(fp_line
			(start 0.508 -0.9398)
			(end 0.508 0.9398)
			(stroke
				(width 0.1524)
				(type default)
			)
			(layer "B.SilkS")
		)
		(fp_rect
			(start 0.508 0.9398)
			(end -0.508 -0.9398)
			(stroke
				(width 0)
				(type default)
			)
			(fill no)
			(layer "B.CrtYd")
		)
		(fp_rect
			(start 0.508 0.9398)
			(end -0.508 -0.9398)
			(stroke
				(width 0)
				(type default)
			)
			(fill no)
			(layer "B.Fab")
		)
		(pad "1" smd custom
			(at 0 -0.4445 90)
			(size 0.1397 0.1397)
			(layers "B.Cu" "B.Mask" "B.Paste")
			(net "BMC_I2C8_CLKBUF1_SCL")
			(options
				(clearance outline)
				(anchor circle)
			)
			(primitives
				(gr_poly
					(pts
						(arc
							(start -0.1778 0.2794)
							(mid -0.249642 0.249642)
							(end -0.2794 0.1778)
						)
						(arc
							(start -0.2794 -0.1778)
							(mid -0.249642 -0.249642)
							(end -0.1778 -0.2794)
						)
						(arc
							(start 0.1778 -0.2794)
							(mid 0.249642 -0.249642)
							(end 0.2794 -0.1778)
						)
						(arc
							(start 0.2794 0.1778)
							(mid 0.249642 0.249642)
							(end 0.1778 0.2794)
						)
					)
					(width 0)
					(fill yes)
				)
			)
		)
		(pad "2" smd custom
			(at 0 0.4445 90)
			(size 0.1397 0.1397)
			(layers "B.Cu" "B.Mask" "B.Paste")
			(net "BMC0_SMB8_CLK")
			(options
				(clearance outline)
				(anchor circle)
			)
			(primitives
				(gr_poly
					(pts
						(arc
							(start -0.1778 0.2794)
							(mid -0.249642 0.249642)
							(end -0.2794 0.1778)
						)
						(arc
							(start -0.2794 -0.1778)
							(mid -0.249642 -0.249642)
							(end -0.1778 -0.2794)
						)
						(arc
							(start 0.1778 -0.2794)
							(mid 0.249642 -0.249642)
							(end 0.2794 -0.1778)
						)
						(arc
							(start 0.2794 0.1778)
							(mid 0.249642 0.249642)
							(end 0.1778 0.2794)
						)
					)
					(width 0)
					(fill yes)
				)
			)
		)
	)
	(footprint ""
		(layer "B.Cu")
		(at 211.2772 -45.6438 90)
		(property "Reference" "C729"
			(at 0 0 90)
			(layer "B.SilkS")
			(hide yes)
			(effects
				(font
					(size 1.27 1.27)
				)
				(justify mirror)
			)
		)
		(property "Value" "SCD22U10V2KX-1GP"
			(at -1.1811 -2.7051 90)
			(unlocked yes)
			(layer "B.Fab")
			(hide yes)
			(effects
				(font
					(size 1.016 1.016)
					(thickness 0.1524)
				)
				(justify mirror)
			)
		)
		(property "Device Type" "C402H22"
			(at -1.1811 -4.2291 90)
			(unlocked yes)
			(layer "B.Fab")
			(hide yes)
			(effects
				(font
					(size 1.016 1.016)
					(thickness 0.1524)
				)
				(justify mirror)
			)
		)
		(duplicate_pad_numbers_are_jumpers no)
		(fp_rect
			(start 0.4318 0.9525)
			(end -0.4318 -0.9525)
			(stroke
				(width 0)
				(type default)
			)
			(fill no)
			(layer "B.CrtYd")
		)
		(fp_rect
			(start 0.4318 0.9525)
			(end -0.4318 -0.9525)
			(stroke
				(width 0)
				(type default)
			)
			(fill no)
			(layer "B.Fab")
		)
		(pad "1" smd custom
			(at 0 -0.4445 270)
			(size 0.1524 0.1524)
			(layers "B.Cu" "B.Mask" "B.Paste")
			(net "BMC_PETXP")
			(options
				(clearance outline)
				(anchor circle)
			)
			(primitives
				(gr_poly
					(pts
						(arc
							(start 0.3048 0.2032)
							(mid 0.275042 0.275042)
							(end 0.2032 0.3048)
						)
						(arc
							(start -0.2032 0.3048)
							(mid -0.275042 0.275042)
							(end -0.3048 0.2032)
						)
						(arc
							(start -0.3048 -0.2032)
							(mid -0.275042 -0.275042)
							(end -0.2032 -0.3048)
						)
						(arc
							(start 0.2032 -0.3048)
							(mid 0.275042 -0.275042)
							(end 0.3048 -0.2032)
						)
					)
					(width 0)
					(fill yes)
				)
			)
		)
		(pad "2" smd custom
			(at 0 0.4445 270)
			(size 0.1524 0.1524)
			(layers "B.Cu" "B.Mask" "B.Paste")
			(net "PCIE_RX_P76")
			(options
				(clearance outline)
				(anchor circle)
			)
			(primitives
				(gr_poly
					(pts
						(arc
							(start 0.3048 0.2032)
							(mid 0.275042 0.275042)
							(end 0.2032 0.3048)
						)
						(arc
							(start -0.2032 0.3048)
							(mid -0.275042 0.275042)
							(end -0.3048 0.2032)
						)
						(arc
							(start -0.3048 -0.2032)
							(mid -0.275042 -0.275042)
							(end -0.2032 -0.3048)
						)
						(arc
							(start 0.2032 -0.3048)
							(mid 0.275042 -0.275042)
							(end 0.3048 -0.2032)
						)
					)
					(width 0)
					(fill yes)
				)
			)
		)
	)
	(footprint ""
		(layer "B.Cu")
		(at 252.603 -48.988472 -90)
		(property "Reference" "C609"
			(at 0 0 90)
			(layer "B.SilkS")
			(hide yes)
			(effects
				(font
					(size 1.27 1.27)
				)
				(justify mirror)
			)
		)
		(property "Value" "SCD1U16V1KX-1-GP"
			(at 2.8321 -1.7399 270)
			(unlocked yes)
			(layer "B.Fab")
			(hide yes)
			(effects
				(font
					(size 1.016 1.016)
					(thickness 0.1524)
				)
				(justify mirror)
			)
		)
		(property "Device Type" "C0201H13"
			(at 2.8321 -3.2639 270)
			(unlocked yes)
			(layer "B.Fab")
			(hide yes)
			(effects
				(font
					(size 1.016 1.016)
					(thickness 0.1524)
				)
				(justify mirror)
			)
		)
		(duplicate_pad_numbers_are_jumpers no)
		(fp_rect
			(start 0.2794 0.6477)
			(end -0.2794 -0.6477)
			(stroke
				(width 0)
				(type default)
			)
			(fill no)
			(layer "B.CrtYd")
		)
		(fp_rect
			(start 0.2794 0.6477)
			(end -0.2794 -0.6477)
			(stroke
				(width 0)
				(type default)
			)
			(fill no)
			(layer "B.Fab")
		)
		(pad "1" smd custom
			(at 0 -0.2794 90)
			(size 0.0762 0.0762)
			(layers "B.Cu" "B.Mask" "B.Paste")
			(net "DUT_AVD_PCIE")
			(options
				(clearance outline)
				(anchor circle)
			)
			(primitives
				(gr_poly
					(pts
						(arc
							(start 0.1524 0.127)
							(mid 0.137521 0.162921)
							(end 0.1016 0.1778)
						)
						(arc
							(start -0.1016 0.1778)
							(mid -0.137521 0.162921)
							(end -0.1524 0.127)
						)
						(arc
							(start -0.1524 -0.127)
							(mid -0.137521 -0.162921)
							(end -0.1016 -0.1778)
						)
						(arc
							(start 0.1016 -0.1778)
							(mid 0.137521 -0.162921)
							(end 0.1524 -0.127)
						)
					)
					(width 0)
					(fill yes)
				)
			)
		)
		(pad "2" smd custom
			(at 0 0.2794 90)
			(size 0.0762 0.0762)
			(layers "B.Cu" "B.Mask" "B.Paste")
			(net "GND")
			(options
				(clearance outline)
				(anchor circle)
			)
			(primitives
				(gr_poly
					(pts
						(arc
							(start 0.1524 0.127)
							(mid 0.137521 0.162921)
							(end 0.1016 0.1778)
						)
						(arc
							(start -0.1016 0.1778)
							(mid -0.137521 0.162921)
							(end -0.1524 0.127)
						)
						(arc
							(start -0.1524 -0.127)
							(mid -0.137521 -0.162921)
							(end -0.1016 -0.1778)
						)
						(arc
							(start 0.1016 -0.1778)
							(mid 0.137521 -0.162921)
							(end 0.1524 -0.127)
						)
					)
					(width 0)
					(fill yes)
				)
			)
		)
	)
	(footprint ""
		(layer "B.Cu")
		(at 163.058602 -60.098432)
		(property "Reference" "PR174"
			(at 0 0 0)
			(layer "B.SilkS")
			(hide yes)
			(effects
				(font
					(size 1.27 1.27)
				)
				(justify mirror)
			)
		)
		(property "Value" "2K21R2F-GP"
			(at -0.064008 -3.993896 0)
			(unlocked yes)
			(layer "B.Fab")
			(hide yes)
			(effects
				(font
					(size 1.016 1.016)
					(thickness 0.1524)
				)
				(justify mirror)
			)
		)
		(property "Device Type" "R402H16"
			(at -0.064008 -5.517896 0)
			(unlocked yes)
			(layer "B.Fab")
			(hide yes)
			(effects
				(font
					(size 1.016 1.016)
					(thickness 0.1524)
				)
				(justify mirror)
			)
		)
		(duplicate_pad_numbers_are_jumpers no)
		(fp_line
			(start -0.508 -0.9398)
			(end 0.508 -0.9398)
			(stroke
				(width 0.1524)
				(type default)
			)
			(layer "B.SilkS")
		)
		(fp_line
			(start 0.508 -0.9398)
			(end 0.508 0.9398)
			(stroke
				(width 0.1524)
				(type default)
			)
			(layer "B.SilkS")
		)
		(fp_rect
			(start 0.508 0.9398)
			(end -0.508 -0.9398)
			(stroke
				(width 0)
				(type default)
			)
			(fill no)
			(layer "B.CrtYd")
		)
		(fp_rect
			(start 0.508 0.9398)
			(end -0.508 -0.9398)
			(stroke
				(width 0)
				(type default)
			)
			(fill no)
			(layer "B.Fab")
		)
		(pad "1" smd custom
			(at 0 -0.4445 180)
			(size 0.1397 0.1397)
			(layers "B.Cu" "B.Mask" "B.Paste")
			(net "P0V9_LX")
			(options
				(clearance outline)
				(anchor circle)
			)
			(primitives
				(gr_poly
					(pts
						(arc
							(start -0.1778 0.2794)
							(mid -0.249642 0.249642)
							(end -0.2794 0.1778)
						)
						(arc
							(start -0.2794 -0.1778)
							(mid -0.249642 -0.249642)
							(end -0.1778 -0.2794)
						)
						(arc
							(start 0.1778 -0.2794)
							(mid 0.249642 -0.249642)
							(end 0.2794 -0.1778)
						)
						(arc
							(start 0.2794 0.1778)
							(mid 0.249642 0.249642)
							(end 0.1778 0.2794)
						)
					)
					(width 0)
					(fill yes)
				)
			)
		)
		(pad "2" smd custom
			(at 0 0.4445 180)
			(size 0.1397 0.1397)
			(layers "B.Cu" "B.Mask" "B.Paste")
			(net "P0V9_SW_R")
			(options
				(clearance outline)
				(anchor circle)
			)
			(primitives
				(gr_poly
					(pts
						(arc
							(start -0.1778 0.2794)
							(mid -0.249642 0.249642)
							(end -0.2794 0.1778)
						)
						(arc
							(start -0.2794 -0.1778)
							(mid -0.249642 -0.249642)
							(end -0.1778 -0.2794)
						)
						(arc
							(start 0.1778 -0.2794)
							(mid 0.249642 -0.249642)
							(end 0.2794 -0.1778)
						)
						(arc
							(start 0.2794 0.1778)
							(mid 0.249642 0.249642)
							(end 0.1778 0.2794)
						)
					)
					(width 0)
					(fill yes)
				)
			)
		)
	)
	(footprint ""
		(layer "B.Cu")
		(at 127.807212 -199.753474)
		(property "Reference" "C3210"
			(at 0 0 0)
			(layer "B.SilkS")
			(hide yes)
			(effects
				(font
					(size 1.27 1.27)
				)
				(justify mirror)
			)
		)
		(property "Value" "SCD1U25V2KX-2-GP"
			(at -1.1811 -2.7051 0)
			(unlocked yes)
			(layer "B.Fab")
			(hide yes)
			(effects
				(font
					(size 1.016 1.016)
					(thickness 0.1524)
				)
				(justify mirror)
			)
		)
		(property "Device Type" "C402H22"
			(at -1.1811 -4.2291 0)
			(unlocked yes)
			(layer "B.Fab")
			(hide yes)
			(effects
				(font
					(size 1.016 1.016)
					(thickness 0.1524)
				)
				(justify mirror)
			)
		)
		(duplicate_pad_numbers_are_jumpers no)
		(fp_rect
			(start 0.4318 0.9525)
			(end -0.4318 -0.9525)
			(stroke
				(width 0)
				(type default)
			)
			(fill no)
			(layer "B.CrtYd")
		)
		(fp_rect
			(start 0.4318 0.9525)
			(end -0.4318 -0.9525)
			(stroke
				(width 0)
				(type default)
			)
			(fill no)
			(layer "B.Fab")
		)
		(pad "1" smd custom
			(at 0 -0.4445 180)
			(size 0.1524 0.1524)
			(layers "B.Cu" "B.Mask" "B.Paste")
			(net "P3V3_STBY")
			(options
				(clearance outline)
				(anchor circle)
			)
			(primitives
				(gr_poly
					(pts
						(arc
							(start 0.3048 0.2032)
							(mid 0.275042 0.275042)
							(end 0.2032 0.3048)
						)
						(arc
							(start -0.2032 0.3048)
							(mid -0.275042 0.275042)
							(end -0.3048 0.2032)
						)
						(arc
							(start -0.3048 -0.2032)
							(mid -0.275042 -0.275042)
							(end -0.2032 -0.3048)
						)
						(arc
							(start 0.2032 -0.3048)
							(mid 0.275042 -0.275042)
							(end 0.3048 -0.2032)
						)
					)
					(width 0)
					(fill yes)
				)
			)
		)
		(pad "2" smd custom
			(at 0 0.4445 180)
			(size 0.1524 0.1524)
			(layers "B.Cu" "B.Mask" "B.Paste")
			(net "GND")
			(options
				(clearance outline)
				(anchor circle)
			)
			(primitives
				(gr_poly
					(pts
						(arc
							(start 0.3048 0.2032)
							(mid 0.275042 0.275042)
							(end 0.2032 0.3048)
						)
						(arc
							(start -0.2032 0.3048)
							(mid -0.275042 0.275042)
							(end -0.3048 0.2032)
						)
						(arc
							(start -0.3048 -0.2032)
							(mid -0.275042 -0.275042)
							(end -0.2032 -0.3048)
						)
						(arc
							(start 0.2032 -0.3048)
							(mid 0.275042 -0.275042)
							(end 0.3048 -0.2032)
						)
					)
					(width 0)
					(fill yes)
				)
			)
		)
	)
)
